FILE_TYPE = MACRO_DRAWING;
SET COLOR_WIRE YELLOW;
SET COLOR_PROP ORANGE;
SET COLOR_DOT WHITE;
SET COLOR_ARC YELLOW;
SET COLOR_BODY GREEN;
SET COLOR_NOTE PURPLE;
SET PROP_DISPLAY VALUE;
SET PAGE_NUMBER P6;
FORCEADD QUANTA_TITLE_BLOCK_C..1
(-100 100);
FORCEPROP 1 LAST CUSTOM_TXT_CDS <NAME_2>
J 0
(-3275 150);
FORCEPROP 1 LAST CUSTOM_TXT_CDS <NAME_1>
J 0
(-3275 275);
FORCEPROP 1 LAST CUSTOM_TXT_CDS <Q_NUMBER>
J 0
(-1503 203);
DISPLAY 1.212766 (-1503 203);
FORCEPROP 1 LAST CUSTOM_TXT_CDS <Q_PROJ>
J 0
(-2482 202);
DISPLAY 1.212766 (-2482 202);
FORCEPROP 1 LAST CUSTOM_TXT_CDS <Q_REV>
J 0
(-284 203);
DISPLAY 1.212766 (-284 203);
FORCEPROP 1 LAST CUSTOM_TXT_CDS <CON_LAST_MODIFIED>
J 0
(-1985 115);
DISPLAY 0.978723 (-1985 115);
FORCEPROP 1 LAST CUSTOM_TXT_CDS <CON_PAGE_NUM> OF <CON_TOTAL_PAGES>
J 0
(-546 118);
DISPLAY 0.978723 (-546 118);
FORCEPROP 1 LAST Q_TITLE BLOCK DIAGRAM - POWER
J 0
(-9400 150);
DISPLAY 2.446809 (-9400 150);
PAINT GREEN (-9400 150);
FORCEPROP 1 LAST Q_DEPT BU9
J 1
(-3863 149);
DISPLAY 1.957447 (-3863 149);
PAINT GREEN (-3863 149);
FORCEPROP 2 LAST CDS_LIB pure_quanta
J 0
(-100 100);
DISPLAY INVISIBLE (-100 100);
FORCEPROP 1 LAST CDS_LMAN_SYM_OUTLINE -9475,6775,100,-125
J 0
(-100 100);
DISPLAY 0.468085 (-100 100);
PAINT GREEN (-100 100);
DISPLAY INVISIBLE (-100 100);
FORCEPROP 2 LAST PAGE_BORDER TRUE
J 0
(-7990 5350);
DISPLAY 0.638298 (-7990 5350);
PAINT PINK (-7990 5350);
DISPLAY INVISIBLE (-7990 5350);
FORCEPROP 1 LAST COMMENT_BODY TRUE
J 0
(-88 87);
DISPLAY 0.978723 (-88 87);
PAINT GREEN (-88 87);
DISPLAY INVISIBLE (-88 87);
FORCEPROP 2 LAST CDS_XR_PAGE_TITLE CR-6 : @T6G_MB_LIB.T6G(SCH_1):PAGE6
J 0
(-7990 5350);
DISPLAY 0.638298 (-7990 5350);
PAINT PINK (-7990 5350);
DISPLAY INVISIBLE (-7990 5350);
FORCEPROP 2 LAST CUSTOM_TXT_CDS <XR_PAGE_TITLE>
J 0
(-7990 5350);
DISPLAY 0.638298 (-7990 5350);
PAINT PINK (-7990 5350);
DISPLAY INVISIBLE (-7990 5350);
FORCEPROP 0 LAST CDS_CON_LAST_MODIFIED Tue Mar 08 15:46:35 2022
J 0
(-1985 115);
DISPLAY INVISIBLE (-1985 115);
QUIT
